FILE_TYPE = MACRO_DRAWING;
SET COLOR_WIRE YELLOW;
SET COLOR_PROP ORANGE;
SET COLOR_DOT WHITE;
SET COLOR_ARC YELLOW;
SET COLOR_BODY GREEN;
SET COLOR_NOTE PURPLE;
SET PROP_DISPLAY VALUE;
SET PAGE_NUMBER P216;
FORCEADD OFFPAGE..6
(-8575 3400);
FORCEPROP 2 LAST $XR1 241 
J 0
(-8975 3400);
DISPLAY 0.638298 (-8975 3400);
PAINT MONO (-8975 3400);
FORCEPROP 2 LAST $XR0 240 
J 0
(-8855 3400);
DISPLAY 0.638298 (-8855 3400);
PAINT MONO (-8855 3400);
FORCEPROP 1 LAST COMMENT_BODY TRUE
J 0
(-8475 3325);
DISPLAY 0.872340 (-8475 3325);
PAINT GREEN (-8475 3325);
DISPLAY INVISIBLE (-8475 3325);
FORCEPROP 1 LAST OFFPAGE TRUE
J 0
(-8250 3275);
DISPLAY 0.872340 (-8250 3275);
DISPLAY INVISIBLE (-8250 3275);
FORCEPROP 2 LAST CDS_LIB standard
J 0
(-8575 3400);
DISPLAY INVISIBLE (-8575 3400);
FORCEPROP 2 LAST PATH I1
J 0
(-8850 3450);
DISPLAY 1.021277 (-8850 3450);
DISPLAY INVISIBLE (-8850 3450);
FORCEADD Q_CAP..1
(-8075 3900);
FORCEPROP 1 LAST PART_NUMBER CH4104K1B00
J 0
(-8025 3750);
DISPLAY 0.510638 (-8025 3750);
DISPLAY INVISIBLE (-8025 3750);
FORCEPROP 1 LAST TOLERANCE 10%
J 0
(-8025 3850);
DISPLAY 0.510638 (-8025 3850);
FORCEPROP 1 LAST PACK_TYPE 0402
J 0
(-8025 3700);
DISPLAY 0.510638 (-8025 3700);
FORCEPROP 1 LAST MATERIAL X7R
J 0
(-8025 3800);
DISPLAY 0.510638 (-8025 3800);
FORCEPROP 1 LAST VOLTAGE 25V
J 0
(-8025 3900);
DISPLAY 0.510638 (-8025 3900);
FORCEPROP 1 LAST VALUE 0.1UF
J 0
(-8025 3950);
DISPLAY 0.510638 (-8025 3950);
FORCEPROP 1 LAST $LOCATION C1859
J 0
(-8025 4000);
DISPLAY 0.978723 (-8025 4000);
FORCEPROP 1 LASTPIN (-8075 4000) $PN 1
J 0
(-8065 3980);
DISPLAY 0.787234 (-8065 3980);
FORCEPROP 1 LASTPIN (-8075 3800) $PN 2
J 0
(-8065 3780);
DISPLAY 0.787234 (-8065 3780);
FORCEPROP 2 LAST CDS_LIB pure_quanta
J 0
(-8075 3900);
PAINT MONO (-8075 3900);
DISPLAY INVISIBLE (-8075 3900);
FORCEPROP 1 LAST PATH I10
J 0
(-8025 4050);
DISPLAY 0.978723 (-8025 4050);
PAINT WHITE (-8025 4050);
DISPLAY INVISIBLE (-8025 4050);
FORCEPROP 2 LAST CDS_LOCATION C1859
J 0
(-8025 4100);
DISPLAY 1.021277 (-8025 4100);
DISPLAY INVISIBLE (-8025 4100);
FORCEPROP 2 LAST $SEC 1
J 0
(-8025 4100);
DISPLAY 0.680851 (-8025 4100);
PAINT MONO (-8025 4100);
DISPLAY INVISIBLE (-8025 4100);
FORCEPROP 2 LAST CDS_SEC 1
J 0
(-8025 4100);
DISPLAY 1.021277 (-8025 4100);
DISPLAY INVISIBLE (-8025 4100);
FORCEADD Q_CAP..1
(-6400 3900);
FORCEPROP 1 LAST PART_NUMBER CH4104K1B00
J 0
(-6350 3750);
DISPLAY 0.510638 (-6350 3750);
DISPLAY INVISIBLE (-6350 3750);
FORCEPROP 1 LAST VOLTAGE 25V
J 0
(-6350 3900);
DISPLAY 0.510638 (-6350 3900);
FORCEPROP 1 LAST PACK_TYPE 0402
J 0
(-6350 3700);
DISPLAY 0.510638 (-6350 3700);
FORCEPROP 1 LAST VALUE 0.1UF
J 0
(-6350 3950);
DISPLAY 0.510638 (-6350 3950);
FORCEPROP 1 LAST TOLERANCE 10%
J 0
(-6350 3850);
DISPLAY 0.510638 (-6350 3850);
FORCEPROP 1 LAST MATERIAL X7R
J 0
(-6350 3800);
DISPLAY 0.510638 (-6350 3800);
FORCEPROP 1 LAST $LOCATION C1861
J 0
(-6350 4000);
DISPLAY 0.978723 (-6350 4000);
FORCEPROP 1 LASTPIN (-6400 4000) $PN 1
J 0
(-6390 3980);
DISPLAY 0.787234 (-6390 3980);
PAINT MONO (-6390 3980);
FORCEPROP 1 LASTPIN (-6400 3800) $PN 2
J 0
(-6390 3780);
DISPLAY 0.787234 (-6390 3780);
PAINT MONO (-6390 3780);
FORCEPROP 2 LAST CDS_LIB pure_quanta
J 0
(-6400 3900);
DISPLAY INVISIBLE (-6400 3900);
FORCEPROP 1 LAST PATH I11
J 0
(-6350 4050);
DISPLAY 0.978723 (-6350 4050);
PAINT WHITE (-6350 4050);
DISPLAY INVISIBLE (-6350 4050);
FORCEPROP 0 LAST CDS_LOCATION C1861
J 0
(-6350 4050);
DISPLAY 1.021277 (-6350 4050);
DISPLAY INVISIBLE (-6350 4050);
FORCEPROP 0 LAST $SEC 1
J 0
(-6350 4050);
DISPLAY 0.680851 (-6350 4050);
PAINT MONO (-6350 4050);
DISPLAY INVISIBLE (-6350 4050);
FORCEPROP 0 LAST CDS_SEC 1
J 0
(-6350 4050);
DISPLAY 1.021277 (-6350 4050);
DISPLAY INVISIBLE (-6350 4050);
FORCEADD OFFPAGE..6
(-8550 5225);
FORCEPROP 2 LAST $XR1 241 
J 0
(-8950 5225);
DISPLAY 0.638298 (-8950 5225);
PAINT MONO (-8950 5225);
FORCEPROP 2 LAST $XR0 240 
J 0
(-8830 5225);
DISPLAY 0.638298 (-8830 5225);
PAINT MONO (-8830 5225);
FORCEPROP 2 LAST CDS_LIB standard
J 0
(-8550 5225);
DISPLAY INVISIBLE (-8550 5225);
FORCEPROP 1 LAST OFFPAGE TRUE
J 0
(-8225 5100);
DISPLAY 0.872340 (-8225 5100);
DISPLAY INVISIBLE (-8225 5100);
FORCEPROP 1 LAST COMMENT_BODY TRUE
J 0
(-8450 5150);
DISPLAY 0.872340 (-8450 5150);
PAINT GREEN (-8450 5150);
DISPLAY INVISIBLE (-8450 5150);
FORCEPROP 2 LAST PATH I12
J 0
(-8825 5275);
DISPLAY 1.021277 (-8825 5275);
DISPLAY INVISIBLE (-8825 5275);
FORCEADD OFFPAGE..1
(-8550 5325);
FORCEPROP 2 LAST $XR1 241 
J 0
(-8922 5325);
DISPLAY 0.638298 (-8922 5325);
PAINT MONO (-8922 5325);
FORCEPROP 2 LAST $XR0 240 
J 0
(-8802 5325);
DISPLAY 0.638298 (-8802 5325);
PAINT MONO (-8802 5325);
FORCEPROP 2 LAST CDS_LIB standard
J 0
(-8550 5325);
DISPLAY INVISIBLE (-8550 5325);
FORCEPROP 1 LAST OFFPAGE TRUE
J 0
(-8225 5200);
DISPLAY 0.872340 (-8225 5200);
PAINT GREEN (-8225 5200);
DISPLAY INVISIBLE (-8225 5200);
FORCEPROP 1 LAST COMMENT_BODY TRUE
J 0
(-8425 5225);
DISPLAY 0.872340 (-8425 5225);
PAINT GREEN (-8425 5225);
DISPLAY INVISIBLE (-8425 5225);
FORCEPROP 2 LAST PATH I13
J 0
(-8800 5375);
DISPLAY 1.021277 (-8800 5375);
DISPLAY INVISIBLE (-8800 5375);
FORCEADD UNIVERSAL_POWER..1
(-7725 4200);
FORCEPROP 3 LASTPIN (-7725 4150) SIG_NAME P3V3_AUX\g
J 0
(-7715 4160);
DISPLAY 0.659574 (-7715 4160);
PAINT MONO (-7715 4160);
DISPLAY INVISIBLE (-7715 4160);
FORCEPROP 1 LAST HDL_POWER P3V3_AUX
J 1
(-7725 4250);
DISPLAY 0.872340 (-7725 4250);
PAINT GREEN (-7725 4250);
FORCEPROP 2 LAST CDS_LIB logical_power
J 0
(-7725 4200);
PAINT MONO (-7725 4200);
DISPLAY INVISIBLE (-7725 4200);
FORCEPROP 1 LAST PATH I14
J 0
(-7675 4225);
DISPLAY 0.872340 (-7675 4225);
PAINT AQUA (-7675 4225);
DISPLAY INVISIBLE (-7675 4225);
FORCEADD UNIVERSAL_GND..1
(-7650 4850);
FORCEPROP 3 LASTPIN (-7650 4900) SIG_NAME GND\g
J 0
(-7640 4910);
DISPLAY 0.659574 (-7640 4910);
PAINT MONO (-7640 4910);
DISPLAY INVISIBLE (-7640 4910);
FORCEPROP 1 LAST HDL_POWER GND
J 1
(-7625 4775);
DISPLAY 0.872340 (-7625 4775);
PAINT GREEN (-7625 4775);
DISPLAY INVISIBLE (-7625 4775);
FORCEPROP 2 LAST CDS_LIB logical_power
J 0
(-7650 4850);
DISPLAY INVISIBLE (-7650 4850);
FORCEPROP 1 LAST PATH I15
J 0
(-7575 4850);
DISPLAY 0.872340 (-7575 4850);
PAINT AQUA (-7575 4850);
DISPLAY INVISIBLE (-7575 4850);
FORCEADD UNIVERSAL_GND..1
(-8050 5500);
FORCEPROP 3 LASTPIN (-8050 5550) SIG_NAME GND\g
J 0
(-8040 5560);
DISPLAY 0.659574 (-8040 5560);
PAINT MONO (-8040 5560);
DISPLAY INVISIBLE (-8040 5560);
FORCEPROP 1 LAST HDL_POWER GND
J 1
(-8025 5425);
DISPLAY 0.872340 (-8025 5425);
PAINT GREEN (-8025 5425);
DISPLAY INVISIBLE (-8025 5425);
FORCEPROP 2 LAST CDS_LIB logical_power
J 0
(-8050 5500);
PAINT MONO (-8050 5500);
DISPLAY INVISIBLE (-8050 5500);
FORCEPROP 1 LAST PATH I16
J 0
(-7975 5500);
DISPLAY 0.872340 (-7975 5500);
PAINT AQUA (-7975 5500);
DISPLAY INVISIBLE (-7975 5500);
FORCEADD Q_CAP..1
(-8050 5725);
FORCEPROP 1 LAST PART_NUMBER CH4104K1B00
J 0
(-8000 5575);
DISPLAY 0.510638 (-8000 5575);
DISPLAY INVISIBLE (-8000 5575);
FORCEPROP 1 LAST PACK_TYPE 0402
J 0
(-8000 5525);
DISPLAY 0.510638 (-8000 5525);
FORCEPROP 1 LAST VOLTAGE 25V
J 0
(-8000 5725);
DISPLAY 0.510638 (-8000 5725);
FORCEPROP 1 LAST MATERIAL X7R
J 0
(-8000 5625);
DISPLAY 0.510638 (-8000 5625);
FORCEPROP 1 LAST TOLERANCE 10%
J 0
(-8000 5675);
DISPLAY 0.510638 (-8000 5675);
FORCEPROP 1 LAST VALUE 0.1UF
J 0
(-8000 5775);
DISPLAY 0.510638 (-8000 5775);
FORCEPROP 1 LAST $LOCATION C1860
J 0
(-8000 5825);
DISPLAY 0.978723 (-8000 5825);
FORCEPROP 1 LASTPIN (-8050 5825) $PN 1
J 0
(-8040 5805);
DISPLAY 0.787234 (-8040 5805);
FORCEPROP 1 LASTPIN (-8050 5625) $PN 2
J 0
(-8040 5605);
DISPLAY 0.787234 (-8040 5605);
FORCEPROP 2 LAST CDS_LIB pure_quanta
J 0
(-8050 5725);
PAINT MONO (-8050 5725);
DISPLAY INVISIBLE (-8050 5725);
FORCEPROP 1 LAST PATH I17
J 0
(-8000 5875);
DISPLAY 0.978723 (-8000 5875);
PAINT WHITE (-8000 5875);
DISPLAY INVISIBLE (-8000 5875);
FORCEPROP 2 LAST CDS_LOCATION C1860
J 0
(-8000 5925);
DISPLAY 1.021277 (-8000 5925);
DISPLAY INVISIBLE (-8000 5925);
FORCEPROP 2 LAST $SEC 1
J 0
(-8000 5925);
DISPLAY 0.680851 (-8000 5925);
PAINT MONO (-8000 5925);
DISPLAY INVISIBLE (-8000 5925);
FORCEPROP 2 LAST CDS_SEC 1
J 0
(-8000 5925);
DISPLAY 1.021277 (-8000 5925);
DISPLAY INVISIBLE (-8000 5925);
FORCEADD UNIVERSAL_POWER..1
(-7700 6025);
FORCEPROP 3 LASTPIN (-7700 5975) SIG_NAME P3V3_AUX\g
J 0
(-7690 5985);
DISPLAY 0.659574 (-7690 5985);
PAINT MONO (-7690 5985);
DISPLAY INVISIBLE (-7690 5985);
FORCEPROP 1 LAST HDL_POWER P3V3_AUX
J 1
(-7700 6075);
DISPLAY 0.872340 (-7700 6075);
PAINT GREEN (-7700 6075);
FORCEPROP 2 LAST CDS_LIB logical_power
J 0
(-7700 6025);
PAINT MONO (-7700 6025);
DISPLAY INVISIBLE (-7700 6025);
FORCEPROP 1 LAST PATH I18
J 0
(-7650 6050);
DISPLAY 0.872340 (-7650 6050);
PAINT AQUA (-7650 6050);
DISPLAY INVISIBLE (-7650 6050);
FORCEADD UNIVERSAL_POWER..1
(-6600 4200);
FORCEPROP 3 LASTPIN (-6600 4150) SIG_NAME P3V3_OCP_V3_2\g
J 0
(-6590 4160);
DISPLAY 0.659574 (-6590 4160);
PAINT MONO (-6590 4160);
DISPLAY INVISIBLE (-6590 4160);
FORCEPROP 1 LAST HDL_POWER P3V3_OCP_V3_2
J 1
(-6600 4250);
DISPLAY 0.872340 (-6600 4250);
PAINT GREEN (-6600 4250);
FORCEPROP 2 LAST CDS_LIB logical_power
J 0
(-6600 4200);
DISPLAY INVISIBLE (-6600 4200);
FORCEPROP 1 LAST PATH I19
J 0
(-6550 4225);
DISPLAY 0.872340 (-6550 4225);
PAINT AQUA (-6550 4225);
DISPLAY INVISIBLE (-6550 4225);
FORCEADD OFFPAGE..1
(-8575 3500);
FORCEPROP 2 LAST $XR1 241 
J 0
(-8947 3500);
DISPLAY 0.638298 (-8947 3500);
PAINT MONO (-8947 3500);
FORCEPROP 2 LAST $XR0 240 
J 0
(-8827 3500);
DISPLAY 0.638298 (-8827 3500);
PAINT MONO (-8827 3500);
FORCEPROP 1 LAST COMMENT_BODY TRUE
J 0
(-8450 3400);
DISPLAY 0.872340 (-8450 3400);
PAINT GREEN (-8450 3400);
DISPLAY INVISIBLE (-8450 3400);
FORCEPROP 1 LAST OFFPAGE TRUE
J 0
(-8250 3375);
DISPLAY 0.872340 (-8250 3375);
PAINT GREEN (-8250 3375);
DISPLAY INVISIBLE (-8250 3375);
FORCEPROP 2 LAST CDS_LIB standard
J 0
(-8575 3500);
DISPLAY INVISIBLE (-8575 3500);
FORCEPROP 2 LAST PATH I2
J 0
(-8825 3550);
DISPLAY 1.021277 (-8825 3550);
DISPLAY INVISIBLE (-8825 3550);
FORCEADD UNIVERSAL_POWER..1
(-6575 6025);
FORCEPROP 3 LASTPIN (-6575 5975) SIG_NAME P3V3_OCP_SFF\g
J 0
(-6565 5985);
DISPLAY 0.659574 (-6565 5985);
PAINT MONO (-6565 5985);
DISPLAY INVISIBLE (-6565 5985);
FORCEPROP 1 LAST HDL_POWER P3V3_OCP_SFF
J 1
(-6575 6075);
DISPLAY 0.872340 (-6575 6075);
PAINT GREEN (-6575 6075);
FORCEPROP 2 LAST CDS_LIB logical_power
J 0
(-6575 6025);
DISPLAY INVISIBLE (-6575 6025);
FORCEPROP 1 LAST PATH I20
J 0
(-6525 6050);
DISPLAY 0.872340 (-6525 6050);
PAINT AQUA (-6525 6050);
DISPLAY INVISIBLE (-6525 6050);
FORCEADD Q_RES..1
(-5825 5075);
FORCEPROP 1 LAST PART_NUMBER CS00002JB13
J 0
(-5925 5125);
DISPLAY 0.404255 (-5925 5125);
DISPLAY INVISIBLE (-5925 5125);
FORCEPROP 1 LAST PACK_TYPE 0402LF
J 0
(-5925 5150);
DISPLAY 0.404255 (-5925 5150);
FORCEPROP 1 LAST WATTAGE 1/16W
J 2
(-5700 5150);
DISPLAY 0.404255 (-5700 5150);
FORCEPROP 1 LAST TOLERANCE 5%
J 0
(-5650 5075);
DISPLAY 0.510638 (-5650 5075);
FORCEPROP 1 LAST VALUE 0
J 2
(-5675 5075);
DISPLAY 0.510638 (-5675 5075);
FORCEPROP 1 LAST MATERIAL CHIP
J 0
(-5575 5075);
DISPLAY 0.510638 (-5575 5075);
FORCEPROP 1 LAST $LOCATION R3263
J 0
(-6050 5075);
DISPLAY 0.638298 (-6050 5075);
FORCEPROP 1 LASTPIN (-5925 5075) $PN 1
J 0
(-5913 5087);
DISPLAY 0.787234 (-5913 5087);
PAINT MONO (-5913 5087);
FORCEPROP 1 LASTPIN (-5725 5075) $PN 2
J 0
(-5763 5087);
DISPLAY 0.787234 (-5763 5087);
PAINT MONO (-5763 5087);
FORCEPROP 2 LAST CDS_LIB pure_quanta
J 0
(-5825 5075);
DISPLAY INVISIBLE (-5825 5075);
FORCEPROP 1 LAST PATH I21
J 0
(-5875 5225);
DISPLAY 0.978723 (-5875 5225);
PAINT WHITE (-5875 5225);
DISPLAY INVISIBLE (-5875 5225);
FORCEPROP 0 LAST CDS_LOCATION R3263
J 0
(-5700 5175);
DISPLAY 1.021277 (-5700 5175);
DISPLAY INVISIBLE (-5700 5175);
FORCEPROP 0 LAST $SEC 1
J 0
(-5700 5175);
DISPLAY 0.680851 (-5700 5175);
PAINT MONO (-5700 5175);
DISPLAY INVISIBLE (-5700 5175);
FORCEPROP 0 LAST CDS_SEC 1
J 0
(-5700 5175);
DISPLAY 1.021277 (-5700 5175);
DISPLAY INVISIBLE (-5700 5175);
FORCEADD OFFPAGE..3
(-4625 5225);
FORCEPROP 2 LAST $XR0 153 
J 0
(-4411 5225);
DISPLAY 0.638298 (-4411 5225);
PAINT MONO (-4411 5225);
FORCEPROP 2 LAST PATH I22
J 0
(-4400 5275);
DISPLAY 1.021277 (-4400 5275);
DISPLAY INVISIBLE (-4400 5275);
FORCEPROP 1 LAST COMMENT_BODY TRUE
J 0
(-4675 5125);
DISPLAY 0.872340 (-4675 5125);
PAINT GREEN (-4675 5125);
DISPLAY INVISIBLE (-4675 5125);
FORCEPROP 1 LAST OFFPAGE TRUE
J 0
(-4300 5100);
DISPLAY 0.872340 (-4300 5100);
PAINT GREEN (-4300 5100);
DISPLAY INVISIBLE (-4300 5100);
FORCEPROP 2 LAST CDS_LIB standard
J 0
(-4625 5225);
DISPLAY INVISIBLE (-4625 5225);
FORCEADD Q_CAP..1
(-6375 5725);
FORCEPROP 1 LAST PART_NUMBER CH4104K1B00
J 0
(-6325 5575);
DISPLAY 0.510638 (-6325 5575);
DISPLAY INVISIBLE (-6325 5575);
FORCEPROP 1 LAST MATERIAL X7R
J 0
(-6325 5625);
DISPLAY 0.510638 (-6325 5625);
FORCEPROP 1 LAST PACK_TYPE 0402
J 0
(-6325 5525);
DISPLAY 0.510638 (-6325 5525);
FORCEPROP 1 LAST VOLTAGE 25V
J 0
(-6325 5725);
DISPLAY 0.510638 (-6325 5725);
FORCEPROP 1 LAST VALUE 0.1UF
J 0
(-6325 5775);
DISPLAY 0.510638 (-6325 5775);
FORCEPROP 1 LAST TOLERANCE 10%
J 0
(-6325 5675);
DISPLAY 0.510638 (-6325 5675);
FORCEPROP 1 LAST $LOCATION C1862
J 0
(-6325 5825);
DISPLAY 0.978723 (-6325 5825);
FORCEPROP 1 LASTPIN (-6375 5825) $PN 1
J 0
(-6365 5805);
DISPLAY 0.787234 (-6365 5805);
PAINT MONO (-6365 5805);
FORCEPROP 1 LASTPIN (-6375 5625) $PN 2
J 0
(-6365 5605);
DISPLAY 0.787234 (-6365 5605);
PAINT MONO (-6365 5605);
FORCEPROP 2 LAST CDS_LIB pure_quanta
J 0
(-6375 5725);
DISPLAY INVISIBLE (-6375 5725);
FORCEPROP 1 LAST PATH I23
J 0
(-6325 5875);
DISPLAY 0.978723 (-6325 5875);
PAINT WHITE (-6325 5875);
DISPLAY INVISIBLE (-6325 5875);
FORCEPROP 0 LAST CDS_LOCATION C1862
J 0
(-6325 5875);
DISPLAY 1.021277 (-6325 5875);
DISPLAY INVISIBLE (-6325 5875);
FORCEPROP 0 LAST $SEC 1
J 0
(-6325 5875);
DISPLAY 0.680851 (-6325 5875);
PAINT MONO (-6325 5875);
DISPLAY INVISIBLE (-6325 5875);
FORCEPROP 0 LAST CDS_SEC 1
J 0
(-6325 5875);
DISPLAY 1.021277 (-6325 5875);
DISPLAY INVISIBLE (-6325 5875);
FORCEADD UNIVERSAL_GND..1
(-6375 5525);
FORCEPROP 3 LASTPIN (-6375 5575) SIG_NAME GND\g
J 0
(-6365 5585);
DISPLAY 0.659574 (-6365 5585);
PAINT MONO (-6365 5585);
DISPLAY INVISIBLE (-6365 5585);
FORCEPROP 2 LAST CDS_LIB logical_power
J 0
(-6375 5525);
DISPLAY INVISIBLE (-6375 5525);
FORCEPROP 1 LAST HDL_POWER GND
J 1
(-6350 5450);
DISPLAY 0.872340 (-6350 5450);
PAINT GREEN (-6350 5450);
DISPLAY INVISIBLE (-6350 5450);
FORCEPROP 1 LAST PATH I24
J 0
(-6300 5525);
DISPLAY 0.872340 (-6300 5525);
PAINT AQUA (-6300 5525);
DISPLAY INVISIBLE (-6300 5525);
FORCEADD OFFPAGE..2
(-4625 5325);
FORCEPROP 2 LAST $XR0 153 
J 0
(-4436 5325);
DISPLAY 0.638298 (-4436 5325);
PAINT MONO (-4436 5325);
FORCEPROP 2 LAST PATH I25
J 0
(-4425 5375);
DISPLAY 1.021277 (-4425 5375);
DISPLAY INVISIBLE (-4425 5375);
FORCEPROP 1 LAST COMMENT_BODY TRUE
J 0
(-4670 5230);
DISPLAY 0.872340 (-4670 5230);
PAINT GREEN (-4670 5230);
DISPLAY INVISIBLE (-4670 5230);
FORCEPROP 1 LAST OFFPAGE TRUE
J 0
(-4300 5200);
DISPLAY 0.872340 (-4300 5200);
PAINT GREEN (-4300 5200);
DISPLAY INVISIBLE (-4300 5200);
FORCEPROP 2 LAST CDS_LIB standard
J 0
(-4625 5325);
DISPLAY INVISIBLE (-4625 5325);
FORCEADD OFFPAGE..1
R 2
(-4750 3250);
FORCEPROP 2 LAST $XR2 163 
J 0
(-4324 3250);
DISPLAY 0.638298 (-4324 3250);
PAINT MONO (-4324 3250);
FORCEPROP 2 LAST $XR1 162 
J 0
(-4444 3250);
DISPLAY 0.638298 (-4444 3250);
PAINT MONO (-4444 3250);
FORCEPROP 2 LAST $XR0 164 
J 0
(-4564 3250);
DISPLAY 0.638298 (-4564 3250);
PAINT MONO (-4564 3250);
FORCEPROP 2 LAST PATH I26
J 0
(-4300 3300);
DISPLAY 1.021277 (-4300 3300);
DISPLAY INVISIBLE (-4300 3300);
FORCEPROP 2 LAST CDS_LIB standard
J 2
(-4750 3250);
DISPLAY INVISIBLE (-4750 3250);
FORCEPROP 1 LAST COMMENT_BODY TRUE
J 2
(-4875 3150);
DISPLAY 0.872340 (-4875 3150);
PAINT GREEN (-4875 3150);
DISPLAY INVISIBLE (-4875 3150);
FORCEPROP 1 LAST OFFPAGE TRUE
J 2
(-5075 3125);
DISPLAY 0.872340 (-5075 3125);
PAINT GREEN (-5075 3125);
DISPLAY INVISIBLE (-5075 3125);
FORCEADD OFFPAGE..1
R 2
(-4625 5075);
FORCEPROP 2 LAST $XR2 157 
J 0
(-4199 5075);
DISPLAY 0.638298 (-4199 5075);
PAINT MONO (-4199 5075);
FORCEPROP 2 LAST $XR1 156 
J 0
(-4319 5075);
DISPLAY 0.638298 (-4319 5075);
PAINT MONO (-4319 5075);
FORCEPROP 2 LAST $XR0 158 
J 0
(-4439 5075);
DISPLAY 0.638298 (-4439 5075);
PAINT MONO (-4439 5075);
FORCEPROP 2 LAST PATH I27
J 0
(-4175 5125);
DISPLAY 1.021277 (-4175 5125);
DISPLAY INVISIBLE (-4175 5125);
FORCEPROP 1 LAST OFFPAGE TRUE
J 2
(-4950 4950);
DISPLAY 0.872340 (-4950 4950);
PAINT GREEN (-4950 4950);
DISPLAY INVISIBLE (-4950 4950);
FORCEPROP 1 LAST COMMENT_BODY TRUE
J 2
(-4750 4975);
DISPLAY 0.872340 (-4750 4975);
PAINT GREEN (-4750 4975);
DISPLAY INVISIBLE (-4750 4975);
FORCEPROP 2 LAST CDS_LIB standard
J 2
(-4625 5075);
DISPLAY INVISIBLE (-4625 5075);
FORCEADD PCA9617ADP..1
(-7125 5275);
FORCEPROP 1 LAST PART_NUMBER AL009617K02
J 0
(-7399 5635);
DISPLAY 0.723404 (-7399 5635);
PAINT GREEN (-7399 5635);
DISPLAY INVISIBLE (-7399 5635);
FORCEPROP 1 LAST MATERIAL IC
J 0
(-7399 5580);
DISPLAY 0.723404 (-7399 5580);
PAINT GREEN (-7399 5580);
FORCEPROP 2 LAST VALUE PCA9617ADP
J 0
(-7375 5725);
DISPLAY 1.021277 (-7375 5725);
FORCEPROP 2 LAST PART_TYPE SMLF
J 0
(-7375 5775);
DISPLAY 1.021277 (-7375 5775);
FORCEPROP 1 LAST $LOCATION U236
J 0
(-7399 5685);
DISPLAY 0.723404 (-7399 5685);
PAINT GREEN (-7399 5685);
FORCEPROP 0 LASTPIN (-6700 5075) $PN 5
J 0
(-6690 5085);
DISPLAY 0.680851 (-6690 5085);
PAINT MONO (-6690 5085);
FORCEPROP 0 LASTPIN (-7550 5075) $PN 4
J 2
(-7560 5085);
DISPLAY 0.680851 (-7560 5085);
PAINT MONO (-7560 5085);
FORCEPROP 0 LASTPIN (-7550 5325) $PN 2
J 2
(-7560 5335);
DISPLAY 0.680851 (-7560 5335);
PAINT MONO (-7560 5335);
FORCEPROP 0 LASTPIN (-6700 5325) $PN 7
J 0
(-6690 5335);
DISPLAY 0.680851 (-6690 5335);
PAINT MONO (-6690 5335);
FORCEPROP 0 LASTPIN (-7550 5225) $PN 3
J 2
(-7560 5235);
DISPLAY 0.680851 (-7560 5235);
PAINT MONO (-7560 5235);
FORCEPROP 0 LASTPIN (-6700 5225) $PN 6
J 0
(-6690 5235);
DISPLAY 0.680851 (-6690 5235);
PAINT MONO (-6690 5235);
FORCEPROP 0 LASTPIN (-7550 5475) $PN 1
J 2
(-7560 5485);
DISPLAY 0.680851 (-7560 5485);
PAINT MONO (-7560 5485);
FORCEPROP 0 LASTPIN (-6700 5475) $PN 8
J 0
(-6690 5485);
DISPLAY 0.680851 (-6690 5485);
PAINT MONO (-6690 5485);
FORCEPROP 2 LAST CDS_LIB pure_quanta
J 0
(-7125 5275);
DISPLAY INVISIBLE (-7125 5275);
FORCEPROP 1 LAST CDS_LMAN_SYM_OUTLINE -275,300,275,-300
J 0
(-7125 5275);
DISPLAY 0.468085 (-7125 5275);
PAINT GREEN (-7125 5275);
DISPLAY INVISIBLE (-7125 5275);
FORCEPROP 1 LAST NEEDS_NO_SIZE TRUE
J 0
(-6850 4975);
DISPLAY 0.468085 (-6850 4975);
PAINT GREEN (-6850 4975);
DISPLAY INVISIBLE (-6850 4975);
FORCEPROP 1 LAST PATH I28
J 0
(-7125 5275);
DISPLAY 0.723404 (-7125 5275);
PAINT GREEN (-7125 5275);
DISPLAY INVISIBLE (-7125 5275);
FORCEPROP 0 LAST CDS_LOCATION U236
J 0
(-7375 5825);
DISPLAY 1.021277 (-7375 5825);
DISPLAY INVISIBLE (-7375 5825);
FORCEPROP 0 LAST $SEC 1
J 0
(-7375 5825);
DISPLAY 0.680851 (-7375 5825);
PAINT MONO (-7375 5825);
DISPLAY INVISIBLE (-7375 5825);
FORCEPROP 0 LAST CDS_SEC 1
J 0
(-7375 5825);
DISPLAY 1.021277 (-7375 5825);
DISPLAY INVISIBLE (-7375 5825);
FORCEADD UNIVERSAL_POWER..1
(-5400 6000);
FORCEPROP 3 LASTPIN (-5400 5950) SIG_NAME P3V3_OCP_SFF\g
J 0
(-5390 5960);
DISPLAY 0.659574 (-5390 5960);
PAINT MONO (-5390 5960);
DISPLAY INVISIBLE (-5390 5960);
FORCEPROP 1 LAST HDL_POWER P3V3_OCP_SFF
J 1
(-5400 6050);
DISPLAY 0.872340 (-5400 6050);
PAINT GREEN (-5400 6050);
FORCEPROP 2 LAST CDS_LIB logical_power
J 0
(-5400 6000);
PAINT MONO (-5400 6000);
DISPLAY INVISIBLE (-5400 6000);
FORCEPROP 1 LAST PATH I29
J 0
(-5350 6025);
DISPLAY 0.872340 (-5350 6025);
PAINT AQUA (-5350 6025);
DISPLAY INVISIBLE (-5350 6025);
FORCEADD UNIVERSAL_GND..1
(-8075 3675);
FORCEPROP 3 LASTPIN (-8075 3725) SIG_NAME GND\g
J 0
(-8065 3735);
DISPLAY 0.659574 (-8065 3735);
PAINT MONO (-8065 3735);
DISPLAY INVISIBLE (-8065 3735);
FORCEPROP 2 LAST CDS_LIB logical_power
J 0
(-8075 3675);
PAINT MONO (-8075 3675);
DISPLAY INVISIBLE (-8075 3675);
FORCEPROP 1 LAST HDL_POWER GND
J 1
(-8050 3600);
DISPLAY 0.872340 (-8050 3600);
PAINT GREEN (-8050 3600);
DISPLAY INVISIBLE (-8050 3600);
FORCEPROP 1 LAST PATH I3
J 0
(-8000 3675);
DISPLAY 0.872340 (-8000 3675);
PAINT AQUA (-8000 3675);
DISPLAY INVISIBLE (-8000 3675);
FORCEADD Q_RES..2
(-5150 5675);
FORCEPROP 1 LAST PART_NUMBER CS24702JB10
J 0
(-5110 5500);
DISPLAY 0.638298 (-5110 5500);
DISPLAY INVISIBLE (-5110 5500);
FORCEPROP 1 LAST VALUE 4.7K
J 0
(-5105 5750);
DISPLAY 0.638298 (-5105 5750);
FORCEPROP 1 LAST TOLERANCE 5%
J 0
(-5105 5700);
DISPLAY 0.638298 (-5105 5700);
FORCEPROP 1 LAST WATTAGE 1/16W
J 0
(-5110 5650);
DISPLAY 0.638298 (-5110 5650);
FORCEPROP 1 LAST PACK_TYPE 0402LF
J 0
(-5125 5550);
DISPLAY 0.638298 (-5125 5550);
FORCEPROP 1 LAST MATERIAL CHIP
J 0
(-5110 5600);
DISPLAY 0.638298 (-5110 5600);
FORCEPROP 1 LAST $LOCATION R3501
J 0
(-5105 5800);
DISPLAY 0.638298 (-5105 5800);
FORCEPROP 1 LASTPIN (-5150 5775) $PN 1
J 0
(-5145 5737);
DISPLAY 0.787234 (-5145 5737);
FORCEPROP 1 LASTPIN (-5150 5575) $PN 2
J 0
(-5145 5585);
DISPLAY 0.787234 (-5145 5585);
FORCEPROP 2 LAST CDS_LIB pure_quanta
J 0
(-5150 5675);
PAINT MONO (-5150 5675);
DISPLAY INVISIBLE (-5150 5675);
FORCEPROP 1 LAST PATH I30
J 0
(-5100 5850);
DISPLAY 0.978723 (-5100 5850);
PAINT WHITE (-5100 5850);
DISPLAY INVISIBLE (-5100 5850);
FORCEPROP 2 LAST CDS_LOCATION R3501
J 0
(-5100 5900);
DISPLAY 1.021277 (-5100 5900);
DISPLAY INVISIBLE (-5100 5900);
FORCEPROP 2 LAST $SEC 1
J 0
(-5100 5900);
DISPLAY 0.680851 (-5100 5900);
PAINT MONO (-5100 5900);
DISPLAY INVISIBLE (-5100 5900);
FORCEPROP 2 LAST CDS_SEC 1
J 0
(-5100 5900);
DISPLAY 1.021277 (-5100 5900);
DISPLAY INVISIBLE (-5100 5900);
FORCEADD Q_RES..2
(-5400 5675);
FORCEPROP 1 LAST PART_NUMBER CS24702JB10
J 0
(-5360 5500);
DISPLAY 0.638298 (-5360 5500);
DISPLAY INVISIBLE (-5360 5500);
FORCEPROP 1 LAST WATTAGE 1/16W
J 0
(-5360 5650);
DISPLAY 0.638298 (-5360 5650);
FORCEPROP 1 LAST TOLERANCE 5%
J 0
(-5355 5700);
DISPLAY 0.638298 (-5355 5700);
FORCEPROP 1 LAST VALUE 4.7K
J 0
(-5355 5750);
DISPLAY 0.638298 (-5355 5750);
FORCEPROP 1 LAST PACK_TYPE 0402LF
J 0
(-5360 5550);
DISPLAY 0.638298 (-5360 5550);
FORCEPROP 1 LAST MATERIAL CHIP
J 0
(-5360 5600);
DISPLAY 0.638298 (-5360 5600);
FORCEPROP 1 LAST $LOCATION R3500
J 0
(-5355 5800);
DISPLAY 0.638298 (-5355 5800);
FORCEPROP 1 LASTPIN (-5400 5775) $PN 1
J 0
(-5395 5737);
DISPLAY 0.787234 (-5395 5737);
FORCEPROP 1 LASTPIN (-5400 5575) $PN 2
J 0
(-5395 5585);
DISPLAY 0.787234 (-5395 5585);
FORCEPROP 2 LAST CDS_LIB pure_quanta
J 0
(-5400 5675);
PAINT MONO (-5400 5675);
DISPLAY INVISIBLE (-5400 5675);
FORCEPROP 1 LAST PATH I31
J 0
(-5350 5850);
DISPLAY 0.978723 (-5350 5850);
PAINT WHITE (-5350 5850);
DISPLAY INVISIBLE (-5350 5850);
FORCEPROP 2 LAST CDS_LOCATION R3500
J 0
(-5350 5900);
DISPLAY 1.021277 (-5350 5900);
DISPLAY INVISIBLE (-5350 5900);
FORCEPROP 2 LAST $SEC 1
J 0
(-5350 5900);
DISPLAY 0.680851 (-5350 5900);
PAINT MONO (-5350 5900);
DISPLAY INVISIBLE (-5350 5900);
FORCEPROP 2 LAST CDS_SEC 1
J 0
(-5350 5900);
DISPLAY 1.021277 (-5350 5900);
DISPLAY INVISIBLE (-5350 5900);
FORCEADD UNIVERSAL_POWER..1
(-5575 4175);
FORCEPROP 3 LASTPIN (-5575 4125) SIG_NAME P3V3_OCP_V3_2\g
J 0
(-5565 4135);
DISPLAY 0.659574 (-5565 4135);
PAINT MONO (-5565 4135);
DISPLAY INVISIBLE (-5565 4135);
FORCEPROP 1 LAST HDL_POWER P3V3_OCP_V3_2
J 1
(-5575 4225);
DISPLAY 0.872340 (-5575 4225);
PAINT GREEN (-5575 4225);
FORCEPROP 1 LAST PATH I32
J 0
(-5525 4200);
DISPLAY 0.872340 (-5525 4200);
PAINT AQUA (-5525 4200);
DISPLAY INVISIBLE (-5525 4200);
FORCEPROP 2 LAST CDS_LIB logical_power
J 0
(-5575 4175);
DISPLAY INVISIBLE (-5575 4175);
FORCEADD Q_RES..2
(-5325 3850);
FORCEPROP 1 LAST PART_NUMBER CS24702JB10
J 0
(-5285 3675);
DISPLAY 0.638298 (-5285 3675);
DISPLAY INVISIBLE (-5285 3675);
FORCEPROP 1 LAST MATERIAL CHIP
J 0
(-5285 3775);
DISPLAY 0.638298 (-5285 3775);
FORCEPROP 1 LAST PACK_TYPE 0402LF
J 0
(-5300 3725);
DISPLAY 0.638298 (-5300 3725);
FORCEPROP 1 LAST TOLERANCE 5%
J 0
(-5280 3875);
DISPLAY 0.638298 (-5280 3875);
FORCEPROP 1 LAST VALUE 4.7K
J 0
(-5280 3925);
DISPLAY 0.638298 (-5280 3925);
FORCEPROP 1 LAST WATTAGE 1/16W
J 0
(-5285 3825);
DISPLAY 0.638298 (-5285 3825);
FORCEPROP 1 LAST $LOCATION R3520
J 0
(-5280 3975);
DISPLAY 0.978723 (-5280 3975);
FORCEPROP 1 LASTPIN (-5325 3950) $PN 1
J 0
(-5320 3912);
DISPLAY 0.787234 (-5320 3912);
PAINT MONO (-5320 3912);
FORCEPROP 1 LASTPIN (-5325 3750) $PN 2
J 0
(-5320 3760);
DISPLAY 0.787234 (-5320 3760);
PAINT MONO (-5320 3760);
FORCEPROP 1 LAST PATH I33
J 0
(-5275 4025);
DISPLAY 0.978723 (-5275 4025);
PAINT WHITE (-5275 4025);
DISPLAY INVISIBLE (-5275 4025);
FORCEPROP 2 LAST CDS_LIB pure_quanta
J 0
(-5325 3850);
DISPLAY INVISIBLE (-5325 3850);
FORCEPROP 0 LAST CDS_LOCATION R3520
J 0
(-5275 4025);
DISPLAY 1.021277 (-5275 4025);
DISPLAY INVISIBLE (-5275 4025);
FORCEPROP 0 LAST $SEC 1
J 0
(-5275 4025);
DISPLAY 0.680851 (-5275 4025);
PAINT MONO (-5275 4025);
DISPLAY INVISIBLE (-5275 4025);
FORCEPROP 0 LAST CDS_SEC 1
J 0
(-5275 4025);
DISPLAY 1.021277 (-5275 4025);
DISPLAY INVISIBLE (-5275 4025);
FORCEADD Q_RES..2
(-5575 3850);
FORCEPROP 1 LAST PART_NUMBER CS24702JB10
J 0
(-5535 3675);
DISPLAY 0.638298 (-5535 3675);
DISPLAY INVISIBLE (-5535 3675);
FORCEPROP 1 LAST PACK_TYPE 0402LF
J 0
(-5535 3725);
DISPLAY 0.638298 (-5535 3725);
FORCEPROP 1 LAST TOLERANCE 5%
J 0
(-5530 3875);
DISPLAY 0.638298 (-5530 3875);
FORCEPROP 1 LAST VALUE 4.7K
J 0
(-5530 3925);
DISPLAY 0.638298 (-5530 3925);
FORCEPROP 1 LAST WATTAGE 1/16W
J 0
(-5535 3825);
DISPLAY 0.638298 (-5535 3825);
FORCEPROP 1 LAST MATERIAL CHIP
J 0
(-5535 3775);
DISPLAY 0.638298 (-5535 3775);
FORCEPROP 1 LAST $LOCATION R3519
J 0
(-5530 3975);
DISPLAY 0.978723 (-5530 3975);
FORCEPROP 1 LASTPIN (-5575 3950) $PN 1
J 0
(-5570 3912);
DISPLAY 0.787234 (-5570 3912);
PAINT MONO (-5570 3912);
FORCEPROP 1 LASTPIN (-5575 3750) $PN 2
J 0
(-5570 3760);
DISPLAY 0.787234 (-5570 3760);
PAINT MONO (-5570 3760);
FORCEPROP 1 LAST PATH I34
J 0
(-5525 4025);
DISPLAY 0.978723 (-5525 4025);
PAINT WHITE (-5525 4025);
DISPLAY INVISIBLE (-5525 4025);
FORCEPROP 2 LAST CDS_LIB pure_quanta
J 0
(-5575 3850);
DISPLAY INVISIBLE (-5575 3850);
FORCEPROP 0 LAST CDS_LOCATION R3519
J 0
(-5525 4025);
DISPLAY 1.021277 (-5525 4025);
DISPLAY INVISIBLE (-5525 4025);
FORCEPROP 0 LAST $SEC 1
J 0
(-5525 4025);
DISPLAY 0.680851 (-5525 4025);
PAINT MONO (-5525 4025);
DISPLAY INVISIBLE (-5525 4025);
FORCEPROP 0 LAST CDS_SEC 1
J 0
(-5525 4025);
DISPLAY 1.021277 (-5525 4025);
DISPLAY INVISIBLE (-5525 4025);
FORCEADD UNIVERSAL_GND..1
(-7675 3025);
FORCEPROP 3 LASTPIN (-7675 3075) SIG_NAME GND\g
J 0
(-7665 3085);
DISPLAY 0.659574 (-7665 3085);
PAINT MONO (-7665 3085);
DISPLAY INVISIBLE (-7665 3085);
FORCEPROP 2 LAST CDS_LIB logical_power
J 0
(-7675 3025);
DISPLAY INVISIBLE (-7675 3025);
FORCEPROP 1 LAST HDL_POWER GND
J 1
(-7650 2950);
DISPLAY 0.872340 (-7650 2950);
PAINT GREEN (-7650 2950);
DISPLAY INVISIBLE (-7650 2950);
FORCEPROP 1 LAST PATH I4
J 0
(-7600 3025);
DISPLAY 0.872340 (-7600 3025);
PAINT AQUA (-7600 3025);
DISPLAY INVISIBLE (-7600 3025);
FORCEADD PCA9617ADP..1
(-7150 3450);
FORCEPROP 1 LAST PART_NUMBER AL009617K02
J 0
(-7424 3810);
DISPLAY 0.723404 (-7424 3810);
PAINT GREEN (-7424 3810);
DISPLAY INVISIBLE (-7424 3810);
FORCEPROP 2 LAST PART_TYPE SMLF
J 0
(-7400 3950);
DISPLAY 1.021277 (-7400 3950);
FORCEPROP 1 LAST MATERIAL IC
J 0
(-7424 3755);
DISPLAY 0.723404 (-7424 3755);
PAINT GREEN (-7424 3755);
FORCEPROP 2 LAST VALUE PCA9617ADP
J 0
(-7400 3900);
DISPLAY 1.021277 (-7400 3900);
FORCEPROP 1 LAST $LOCATION U235
J 0
(-7424 3860);
DISPLAY 0.723404 (-7424 3860);
PAINT GREEN (-7424 3860);
FORCEPROP 0 LASTPIN (-6725 3250) $PN 5
J 0
(-6715 3260);
DISPLAY 0.680851 (-6715 3260);
PAINT MONO (-6715 3260);
FORCEPROP 0 LASTPIN (-7575 3250) $PN 4
J 2
(-7585 3260);
DISPLAY 0.680851 (-7585 3260);
PAINT MONO (-7585 3260);
FORCEPROP 0 LASTPIN (-7575 3500) $PN 2
J 2
(-7585 3510);
DISPLAY 0.680851 (-7585 3510);
PAINT MONO (-7585 3510);
FORCEPROP 0 LASTPIN (-6725 3500) $PN 7
J 0
(-6715 3510);
DISPLAY 0.680851 (-6715 3510);
PAINT MONO (-6715 3510);
FORCEPROP 0 LASTPIN (-7575 3400) $PN 3
J 2
(-7585 3410);
DISPLAY 0.680851 (-7585 3410);
PAINT MONO (-7585 3410);
FORCEPROP 0 LASTPIN (-6725 3400) $PN 6
J 0
(-6715 3410);
DISPLAY 0.680851 (-6715 3410);
PAINT MONO (-6715 3410);
FORCEPROP 0 LASTPIN (-7575 3650) $PN 1
J 2
(-7585 3660);
DISPLAY 0.680851 (-7585 3660);
PAINT MONO (-7585 3660);
FORCEPROP 0 LASTPIN (-6725 3650) $PN 8
J 0
(-6715 3660);
DISPLAY 0.680851 (-6715 3660);
PAINT MONO (-6715 3660);
FORCEPROP 1 LAST NEEDS_NO_SIZE TRUE
J 0
(-6875 3150);
DISPLAY 0.468085 (-6875 3150);
PAINT GREEN (-6875 3150);
DISPLAY INVISIBLE (-6875 3150);
FORCEPROP 1 LAST CDS_LMAN_SYM_OUTLINE -275,300,275,-300
J 0
(-7150 3450);
DISPLAY 0.468085 (-7150 3450);
PAINT GREEN (-7150 3450);
DISPLAY INVISIBLE (-7150 3450);
FORCEPROP 2 LAST CDS_LIB pure_quanta
J 0
(-7150 3450);
DISPLAY INVISIBLE (-7150 3450);
FORCEPROP 1 LAST PATH I5
J 0
(-7150 3450);
DISPLAY 0.723404 (-7150 3450);
PAINT GREEN (-7150 3450);
DISPLAY INVISIBLE (-7150 3450);
FORCEPROP 0 LAST CDS_LOCATION U235
J 0
(-7400 4000);
DISPLAY 1.021277 (-7400 4000);
DISPLAY INVISIBLE (-7400 4000);
FORCEPROP 0 LAST $SEC 1
J 0
(-7400 4000);
DISPLAY 0.680851 (-7400 4000);
PAINT MONO (-7400 4000);
DISPLAY INVISIBLE (-7400 4000);
FORCEPROP 0 LAST CDS_SEC 1
J 0
(-7400 4000);
DISPLAY 1.021277 (-7400 4000);
DISPLAY INVISIBLE (-7400 4000);
FORCEADD UNIVERSAL_GND..1
(-6400 3700);
FORCEPROP 3 LASTPIN (-6400 3750) SIG_NAME GND\g
J 0
(-6390 3760);
DISPLAY 0.659574 (-6390 3760);
PAINT MONO (-6390 3760);
DISPLAY INVISIBLE (-6390 3760);
FORCEPROP 1 LAST HDL_POWER GND
J 1
(-6375 3625);
DISPLAY 0.872340 (-6375 3625);
PAINT GREEN (-6375 3625);
DISPLAY INVISIBLE (-6375 3625);
FORCEPROP 2 LAST CDS_LIB logical_power
J 0
(-6400 3700);
DISPLAY INVISIBLE (-6400 3700);
FORCEPROP 1 LAST PATH I6
J 0
(-6325 3700);
DISPLAY 0.872340 (-6325 3700);
PAINT AQUA (-6325 3700);
DISPLAY INVISIBLE (-6325 3700);
FORCEADD Q_RES..1
(-5750 3250);
FORCEPROP 1 LAST PART_NUMBER CS00002JB13
J 0
(-5850 3300);
DISPLAY 0.404255 (-5850 3300);
DISPLAY INVISIBLE (-5850 3300);
FORCEPROP 1 LAST MATERIAL CHIP
J 0
(-5500 3250);
DISPLAY 0.510638 (-5500 3250);
FORCEPROP 1 LAST WATTAGE 1/16W
J 2
(-5625 3325);
DISPLAY 0.404255 (-5625 3325);
FORCEPROP 1 LAST TOLERANCE 5%
J 0
(-5575 3250);
DISPLAY 0.510638 (-5575 3250);
FORCEPROP 1 LAST PACK_TYPE 0402LF
J 0
(-5850 3325);
DISPLAY 0.404255 (-5850 3325);
FORCEPROP 1 LAST VALUE 0
J 2
(-5600 3250);
DISPLAY 0.510638 (-5600 3250);
FORCEPROP 1 LAST $LOCATION R3264
J 0
(-5975 3250);
DISPLAY 0.638298 (-5975 3250);
FORCEPROP 1 LASTPIN (-5850 3250) $PN 1
J 0
(-5838 3262);
DISPLAY 0.787234 (-5838 3262);
PAINT MONO (-5838 3262);
FORCEPROP 1 LASTPIN (-5650 3250) $PN 2
J 0
(-5688 3262);
DISPLAY 0.787234 (-5688 3262);
PAINT MONO (-5688 3262);
FORCEPROP 2 LAST CDS_LIB pure_quanta
J 0
(-5750 3250);
DISPLAY INVISIBLE (-5750 3250);
FORCEPROP 1 LAST PATH I7
J 0
(-5800 3400);
DISPLAY 0.978723 (-5800 3400);
PAINT WHITE (-5800 3400);
DISPLAY INVISIBLE (-5800 3400);
FORCEPROP 0 LAST CDS_LOCATION R3264
J 0
(-5625 3350);
DISPLAY 1.021277 (-5625 3350);
DISPLAY INVISIBLE (-5625 3350);
FORCEPROP 0 LAST $SEC 1
J 0
(-5625 3350);
DISPLAY 0.680851 (-5625 3350);
PAINT MONO (-5625 3350);
DISPLAY INVISIBLE (-5625 3350);
FORCEPROP 0 LAST CDS_SEC 1
J 0
(-5625 3350);
DISPLAY 1.021277 (-5625 3350);
DISPLAY INVISIBLE (-5625 3350);
FORCEADD OFFPAGE..3
(-4750 3400);
FORCEPROP 2 LAST $XR0 159 
J 0
(-4536 3400);
DISPLAY 0.638298 (-4536 3400);
PAINT MONO (-4536 3400);
FORCEPROP 2 LAST PATH I8
J 0
(-4525 3450);
DISPLAY 1.021277 (-4525 3450);
DISPLAY INVISIBLE (-4525 3450);
FORCEPROP 2 LAST CDS_LIB standard
J 0
(-4750 3400);
DISPLAY INVISIBLE (-4750 3400);
FORCEPROP 1 LAST OFFPAGE TRUE
J 0
(-4425 3275);
DISPLAY 0.872340 (-4425 3275);
PAINT GREEN (-4425 3275);
DISPLAY INVISIBLE (-4425 3275);
FORCEPROP 1 LAST COMMENT_BODY TRUE
J 0
(-4800 3300);
DISPLAY 0.872340 (-4800 3300);
PAINT GREEN (-4800 3300);
DISPLAY INVISIBLE (-4800 3300);
FORCEADD OFFPAGE..2
(-4750 3500);
FORCEPROP 2 LAST $XR0 159 
J 0
(-4561 3500);
DISPLAY 0.638298 (-4561 3500);
PAINT MONO (-4561 3500);
FORCEPROP 2 LAST PATH I9
J 0
(-4550 3550);
DISPLAY 1.021277 (-4550 3550);
DISPLAY INVISIBLE (-4550 3550);
FORCEPROP 2 LAST CDS_LIB standard
J 0
(-4750 3500);
DISPLAY INVISIBLE (-4750 3500);
FORCEPROP 1 LAST OFFPAGE TRUE
J 0
(-4425 3375);
DISPLAY 0.872340 (-4425 3375);
PAINT GREEN (-4425 3375);
DISPLAY INVISIBLE (-4425 3375);
FORCEPROP 1 LAST COMMENT_BODY TRUE
J 0
(-4795 3405);
DISPLAY 0.872340 (-4795 3405);
PAINT GREEN (-4795 3405);
DISPLAY INVISIBLE (-4795 3405);
FORCEADD QUANTA_TITLE_BLOCK_C..1
(-2250 -100);
FORCEPROP 0 LAST CDS_CON_LAST_MODIFIED Fri Aug 25 14:04:04 2023
J 0
(-4135 -85);
DISPLAY INVISIBLE (-4135 -85);
FORCEPROP 1 LAST CUSTOM_TXT_CDS <CON_LAST_MODIFIED>
J 0
(-4135 -85);
DISPLAY 0.978723 (-4135 -85);
FORCEPROP 2 LAST CUSTOM_TXT_CDS <XR_PAGE_TITLE>
J 0
(-10140 5150);
DISPLAY 0.638298 (-10140 5150);
PAINT PINK (-10140 5150);
DISPLAY INVISIBLE (-10140 5150);
FORCEPROP 1 LAST CUSTOM_TXT_CDS <NAME_2>
J 0
(-5425 -50);
FORCEPROP 1 LAST CUSTOM_TXT_CDS <NAME_1>
J 0
(-5425 75);
FORCEPROP 1 LAST CUSTOM_TXT_CDS <Q_NUMBER>
J 0
(-3653 3);
DISPLAY 1.212766 (-3653 3);
FORCEPROP 1 LAST CUSTOM_TXT_CDS <Q_PROJ>
J 0
(-4632 2);
DISPLAY 1.212766 (-4632 2);
FORCEPROP 1 LAST CUSTOM_TXT_CDS <Q_REV>
J 0
(-2434 3);
DISPLAY 1.212766 (-2434 3);
FORCEPROP 1 LAST CUSTOM_TXT_CDS <CON_PAGE_NUM> OF <CON_TOTAL_PAGES>
J 0
(-2696 -82);
DISPLAY 0.978723 (-2696 -82);
FORCEPROP 1 LAST Q_TITLE SMBUS - ISOLATED
J 0
(-11616 -74);
DISPLAY 2.446809 (-11616 -74);
PAINT GREEN (-11616 -74);
FORCEPROP 1 LAST Q_DEPT 
J 1
(-6013 -51);
DISPLAY 1.957447 (-6013 -51);
PAINT GREEN (-6013 -51);
FORCEPROP 2 LAST CDS_XR_PAGE_TITLE CR-238 : @S9S_MB_2U_LIB.S9S_MB_2U(SCH_1):PAGE238
J 0
(-10140 5150);
DISPLAY 0.638298 (-10140 5150);
PAINT PINK (-10140 5150);
DISPLAY INVISIBLE (-10140 5150);
FORCEPROP 2 LAST PAGE_BORDER TRUE
J 0
(-10140 5150);
DISPLAY 0.638298 (-10140 5150);
PAINT PINK (-10140 5150);
DISPLAY INVISIBLE (-10140 5150);
FORCEPROP 1 LAST COMMENT_BODY TRUE
J 0
(-2238 -113);
DISPLAY 0.978723 (-2238 -113);
PAINT GREEN (-2238 -113);
DISPLAY INVISIBLE (-2238 -113);
FORCEPROP 1 LAST CDS_LMAN_SYM_OUTLINE -9475,6775,100,-125
J 0
(-2250 -100);
DISPLAY 0.468085 (-2250 -100);
PAINT GREEN (-2250 -100);
DISPLAY INVISIBLE (-2250 -100);
FORCEPROP 2 LAST CDS_LIB pure_quanta
J 0
(-2250 -100);
DISPLAY INVISIBLE (-2250 -100);
WIRE 16 -1 (-6600 4150)(-6600 4075);
WIRE 16 -1 (-5575 4075)(-5575 4125);
WIRE 16 -1 (-5575 4075)(-5325 4075);
WIRE 16 -1 (-5575 3950)(-5575 4075);
WIRE 16 -1 (-5400 5900)(-5400 5950);
WIRE 16 -1 (-5400 5900)(-5150 5900);
WIRE 16 -1 (-5400 5775)(-5400 5900);
WIRE 16 -1 (-6575 5975)(-6575 5900);
WIRE 16 -1 (-7700 5900)(-7700 5975);
WIRE 16 -1 (-7700 5900)(-7700 5475);
WIRE 16 -1 (-7700 5900)(-8050 5900);
WIRE 16 -1 (-7725 4075)(-7725 4150);
WIRE 16 -1 (-7725 4075)(-8075 4075);
WIRE 16 -1 (-7725 4075)(-7725 3650);
WIRE 16 -1 (-8075 3800)(-8075 3725);
WIRE 16 -1 (-7675 3075)(-7675 3250);
WIRE 16 -1 (-6400 3800)(-6400 3750);
WIRE 16 -1 (-7650 4900)(-7650 5075);
WIRE 16 -1 (-8050 5625)(-8050 5550);
WIRE 16 -1 (-6375 5625)(-6375 5575);
WIRE 16 -1 (-8500 5225)(-7550 5225);
FORCEPROP 0 LAST CDS_PHYS_NET_NAME SMB_E1S_0_3V3AUX_SDA
J 0
(-8460 5273);
PAINT MONO (-8460 5273);
DISPLAY INVISIBLE (-8460 5273);
FORCEPROP 2 LAST SIG_NAME SMB_OCP_SFF_3V3AUX_SDA
J 0
(-8335 5235);
DISPLAY 0.510638 (-8335 5235);
PAINT WHITE (-8335 5235);
WIRE 16 -1 (-8500 5325)(-7550 5325);
FORCEPROP 0 LAST CDS_PHYS_NET_NAME SMB_E1S_0_3V3AUX_SCL
J 0
(-8460 5373);
PAINT MONO (-8460 5373);
DISPLAY INVISIBLE (-8460 5373);
FORCEPROP 2 LAST SIG_NAME SMB_OCP_SFF_3V3AUX_SCL
J 0
(-8335 5335);
DISPLAY 0.510638 (-8335 5335);
PAINT WHITE (-8335 5335);
WIRE 16 -1 (-5575 3750)(-5575 3500);
WIRE 16 -1 (-5575 3500)(-4800 3500);
WIRE 16 -1 (-6725 3500)(-5575 3500);
FORCEPROP 0 LAST CDS_PHYS_NET_NAME SMB_E1S_1_3V3AUX_BUF_SCL
J 0
(-6685 3548);
PAINT MONO (-6685 3548);
DISPLAY INVISIBLE (-6685 3548);
FORCEPROP 2 LAST SIG_NAME SMB_OCP_V3_2_3V3AUX_BUF_SCL
J 0
(-6585 3510);
DISPLAY 0.510638 (-6585 3510);
PAINT WHITE (-6585 3510);
WIRE 16 -1 (-5325 3750)(-5325 3400);
WIRE 16 -1 (-5325 3400)(-4800 3400);
WIRE 16 -1 (-6725 3400)(-5325 3400);
FORCEPROP 0 LAST CDS_PHYS_NET_NAME SMB_E1S_1_3V3AUX_BUF_SDA
J 0
(-6685 3448);
PAINT MONO (-6685 3448);
DISPLAY INVISIBLE (-6685 3448);
FORCEPROP 2 LAST SIG_NAME SMB_OCP_V3_2_3V3AUX_BUF_SDA
J 0
(-6585 3410);
DISPLAY 0.510638 (-6585 3410);
PAINT WHITE (-6585 3410);
WIRE 16 -1 (-5850 3250)(-6725 3250);
FORCEPROP 0 LAST CDS_PHYS_NET_NAME FM_E1S_1_SMB_EN
J 0
(-5960 3292);
PAINT MONO (-5960 3292);
DISPLAY INVISIBLE (-5960 3292);
FORCEPROP 2 LAST SIG_NAME HP_LVC3_OCP_V3_2_R_EN
J 0
(-6585 3260);
DISPLAY 0.553191 (-6585 3260);
PAINT WHITE (-6585 3260);
FORCEPROP 0 LAST $PHYS_NET_NAME RST_PCIE_M2_N
J 0
(-5960 3339);
PAINT MONO (-5960 3339);
DISPLAY INVISIBLE (-5960 3339);
WIRE 16 -1 (-5725 5075)(-4675 5075);
FORCEPROP 0 LAST CDS_PHYS_NET_NAME E1S_0_EN
J 0
(-4860 5117);
PAINT MONO (-4860 5117);
DISPLAY INVISIBLE (-4860 5117);
FORCEPROP 2 LAST SIG_NAME HP_LVC3_OCP_V3_1_EN
J 0
(-5335 5085);
DISPLAY 0.553191 (-5335 5085);
PAINT WHITE (-5335 5085);
FORCEPROP 0 LAST $PHYS_NET_NAME RST_PCIE_M2_N
J 0
(-4860 5164);
PAINT MONO (-4860 5164);
DISPLAY INVISIBLE (-4860 5164);
WIRE 16 -1 (-6400 4075)(-6400 4000);
WIRE 16 -1 (-6600 3650)(-6725 3650);
WIRE 16 -1 (-6600 4075)(-6600 3650);
WIRE 16 -1 (-6600 4075)(-6400 4075);
WIRE 16 -1 (-8050 5825)(-8050 5900);
WIRE 16 -1 (-7700 5475)(-7550 5475);
WIRE 16 -1 (-5325 3950)(-5325 4075);
WIRE 16 -1 (-6700 5325)(-5400 5325);
FORCEPROP 0 LAST CDS_PHYS_NET_NAME SMB_E1S_0_3V3AUX_BUF_SCL
J 0
(-6660 5373);
PAINT MONO (-6660 5373);
DISPLAY INVISIBLE (-6660 5373);
FORCEPROP 2 LAST SIG_NAME SMB_OCP_SFF_3V3AUX_BUF_SCL
J 0
(-6560 5335);
DISPLAY 0.510638 (-6560 5335);
PAINT WHITE (-6560 5335);
WIRE 16 -1 (-5400 5325)(-4675 5325);
WIRE 16 -1 (-5400 5575)(-5400 5325);
WIRE 16 -1 (-5150 5775)(-5150 5900);
WIRE 16 -1 (-6700 5225)(-5150 5225);
FORCEPROP 0 LAST CDS_PHYS_NET_NAME SMB_E1S_0_3V3AUX_BUF_SDA
J 0
(-6660 5273);
PAINT MONO (-6660 5273);
DISPLAY INVISIBLE (-6660 5273);
FORCEPROP 2 LAST SIG_NAME SMB_OCP_SFF_3V3AUX_BUF_SDA
J 0
(-6560 5235);
DISPLAY 0.510638 (-6560 5235);
PAINT WHITE (-6560 5235);
WIRE 16 -1 (-4675 5225)(-5150 5225);
WIRE 16 -1 (-5150 5575)(-5150 5225);
WIRE 16 -1 (-6575 5475)(-6700 5475);
WIRE 16 -1 (-6575 5900)(-6575 5475);
WIRE 16 -1 (-6575 5900)(-6375 5900);
WIRE 16 -1 (-6375 5900)(-6375 5825);
WIRE 16 -1 (-7650 5075)(-7550 5075);
WIRE 16 -1 (-5925 5075)(-6700 5075);
FORCEPROP 0 LAST CDS_PHYS_NET_NAME FM_E1S_0_SMB_EN
J 0
(-6035 5117);
PAINT MONO (-6035 5117);
DISPLAY INVISIBLE (-6035 5117);
FORCEPROP 2 LAST SIG_NAME HP_LVC3_OCP_V3_1_R_EN
J 0
(-6660 5085);
DISPLAY 0.553191 (-6660 5085);
PAINT WHITE (-6660 5085);
FORCEPROP 0 LAST $PHYS_NET_NAME RST_PCIE_M2_N
J 0
(-6035 5164);
PAINT MONO (-6035 5164);
DISPLAY INVISIBLE (-6035 5164);
WIRE 16 -1 (-8525 3400)(-7575 3400);
FORCEPROP 0 LAST CDS_PHYS_NET_NAME SMB_E1S_1_3V3AUX_SDA
J 0
(-8485 3448);
PAINT MONO (-8485 3448);
DISPLAY INVISIBLE (-8485 3448);
FORCEPROP 2 LAST SIG_NAME SMB_OCP_V3_2_3V3AUX_SDA
J 0
(-8360 3410);
DISPLAY 0.510638 (-8360 3410);
PAINT WHITE (-8360 3410);
WIRE 16 -1 (-5650 3250)(-4800 3250);
FORCEPROP 0 LAST CDS_PHYS_NET_NAME E1S_1_EN
J 0
(-4985 3292);
PAINT MONO (-4985 3292);
DISPLAY INVISIBLE (-4985 3292);
FORCEPROP 2 LAST SIG_NAME HP_LVC3_OCP_V3_2_EN
J 0
(-5310 3260);
DISPLAY 0.553191 (-5310 3260);
PAINT WHITE (-5310 3260);
FORCEPROP 0 LAST $PHYS_NET_NAME RST_PCIE_M2_N
J 0
(-4985 3339);
PAINT MONO (-4985 3339);
DISPLAY INVISIBLE (-4985 3339);
WIRE 16 -1 (-7725 3650)(-7575 3650);
WIRE 16 -1 (-8075 4000)(-8075 4075);
WIRE 16 -1 (-7675 3250)(-7575 3250);
WIRE 16 -1 (-8525 3500)(-7575 3500);
FORCEPROP 0 LAST CDS_PHYS_NET_NAME SMB_E1S_1_3V3AUX_SCL
J 0
(-8485 3548);
PAINT MONO (-8485 3548);
DISPLAY INVISIBLE (-8485 3548);
FORCEPROP 2 LAST SIG_NAME SMB_OCP_V3_2_3V3AUX_SCL
J 0
(-8360 3510);
DISPLAY 0.510638 (-8360 3510);
PAINT WHITE (-8360 3510);
DOT 1 (-5575 4075);
DOT 1 (-5400 5900);
DOT 1 (-5325 3400);
DOT 1 (-5575 3500);
DOT 1 (-5150 5225);
DOT 1 (-5400 5325);
DOT 1 (-7725 4075);
DOT 1 (-6600 4075);
DOT 1 (-6575 5900);
DOT 1 (-7700 5900);
FORCENOTE
20210818 MODIFY FOR GT
(-11350 6250) 0;
DISPLAY LEFT (-11350 6250);
DISPLAY 2.510638 (-11350 6250);
PAINT PINK (-11350 6250);
QUIT
